(kicad_pcb
	(version 20241229)
	(generator "pcbnew")
	(generator_version "9.0")
	(general
		(thickness 1.292)
		(legacy_teardrops no)
	)
	(paper "A4")
	(title_block
		(title "LPDDR5 Testbed")
		(date "2023-12-19")
		(rev "1.0.0")
		(comment 9 "footprints 66-68 of 160")
	)
	(layers
		(0 "F.Cu" signal)
		(4 "In1.Cu" power)
		(6 "In2.Cu" power)
		(8 "In3.Cu" signal)
		(10 "In4.Cu" signal)
		(2 "B.Cu" signal)
		(9 "F.Adhes" user "F.Adhesive")
		(11 "B.Adhes" user "B.Adhesive")
		(13 "F.Paste" user)
		(15 "B.Paste" user)
		(5 "F.SilkS" user "F.Silkscreen")
		(7 "B.SilkS" user "B.Silkscreen")
		(1 "F.Mask" user)
		(3 "B.Mask" user)
		(17 "Dwgs.User" user "User.Drawings")
		(19 "Cmts.User" user "User.Comments")
		(21 "Eco1.User" user "User.Eco1")
		(23 "Eco2.User" user "User.Eco2")
		(25 "Edge.Cuts" user)
		(27 "Margin" user)
		(31 "F.CrtYd" user "F.Courtyard")
		(29 "B.CrtYd" user "B.Courtyard")
		(35 "F.Fab" user)
		(33 "B.Fab" user)
	)
	(footprint "antmicro-footprints:C_0402_1005Metric"
		(layer "F.Cu")
		(at 135.875 72.25 180)
		(descr "Capacitor SMD 0402")
		(tags "capacitor SMD 0402")
		(property "Reference" "C65"
			(at -3.125 -0.45 0)
			(unlocked yes)
			(layer "F.SilkS")
			(effects
				(font
					(size 0.7 0.7)
					(thickness 0.15)
				)
				(justify right bottom)
			)
		)
		(property "Value" "C_4u7_0402"
			(at -1.022927 2.155213 0)
			(layer "F.Fab")
			(effects
				(font
					(size 0.7 0.7)
					(thickness 0.15)
				)
				(justify right bottom)
			)
		)
		(property "Author" "Antmicro"
			(at 271.75 144.5 0)
			(layer "F.Fab")
			(hide yes)
			(effects
				(font
					(size 1 1)
					(thickness 0.15)
				)
			)
		)
		(property "Dielectric" ""
			(at 271.75 144.5 0)
			(layer "F.Fab")
			(hide yes)
			(effects
				(font
					(size 1 1)
					(thickness 0.15)
				)
			)
		)
		(property "License" "Apache-2.0"
			(at 271.75 144.5 0)
			(layer "F.Fab")
			(hide yes)
			(effects
				(font
					(size 1 1)
					(thickness 0.15)
				)
			)
		)
		(property "MPN" "GRM155R61A475MEAAD"
			(at 271.75 144.5 0)
			(layer "F.Fab")
			(hide yes)
			(effects
				(font
					(size 1 1)
					(thickness 0.15)
				)
			)
		)
		(property "Manufacturer" "Murata"
			(at 271.75 144.5 0)
			(layer "F.Fab")
			(hide yes)
			(effects
				(font
					(size 1 1)
					(thickness 0.15)
				)
			)
		)
		(property "Val" "4u7"
			(at 271.75 144.5 0)
			(layer "F.Fab")
			(hide yes)
			(effects
				(font
					(size 1 1)
					(thickness 0.15)
				)
			)
		)
		(property "Voltage" ""
			(at 271.75 144.5 0)
			(layer "F.Fab")
			(hide yes)
			(effects
				(font
					(size 1 1)
					(thickness 0.15)
				)
			)
		)
		(sheetname "LPDDR5")
		(sheetfile "lpddr5.kicad_sch")
		(attr smd)
		(fp_rect
			(start -0.9659 -0.481258)
			(end 0.9649 0.458742)
			(stroke
				(width 0.05)
				(type solid)
			)
			(fill no)
			(layer "F.CrtYd")
		)
		(fp_line
			(start 0.499 0.248)
			(end -0.499 0.248)
			(stroke
				(width 0.15)
				(type solid)
			)
			(layer "F.Fab")
		)
		(fp_line
			(start 0.499 -0.25)
			(end 0.499 0.248)
			(stroke
				(width 0.15)
				(type solid)
			)
			(layer "F.Fab")
		)
		(fp_line
			(start -0.499 0.248)
			(end -0.499 -0.25)
			(stroke
				(width 0.15)
				(type solid)
			)
			(layer "F.Fab")
		)
		(fp_line
			(start -0.499 -0.25)
			(end 0.499 -0.25)
			(stroke
				(width 0.15)
				(type solid)
			)
			(layer "F.Fab")
		)
		(pad "1" smd roundrect
			(at -0.484 0 180)
			(size 0.59 0.64)
			(layers "F.Cu" "F.Mask" "F.Paste")
			(roundrect_rratio 0.25)
			(net 14 "GND")
			(pintype "passive")
		)
		(pad "2" smd roundrect
			(at 0.484 0 180)
			(size 0.59 0.64)
			(layers "F.Cu" "F.Mask" "F.Paste")
			(roundrect_rratio 0.25)
			(net 13 "+1V05")
			(pintype "passive")
		)
	)
	(footprint "antmicro-footprints:LGA-33_7x7mm_P0.65mm"
		(layer "F.Cu")
		(at 106.6375 67.85 180)
		(property "Reference" "U8"
			(at -4.1625 3.55 0)
			(unlocked yes)
			(layer "F.SilkS")
			(effects
				(font
					(size 0.7 0.7)
					(thickness 0.15)
				)
				(justify left bottom)
			)
		)
		(property "Value" "MPM54304GMN-0001"
			(at 0 5 180)
			(layer "F.Fab")
			(effects
				(font
					(size 0.7 0.7)
					(thickness 0.15)
				)
				(justify left bottom)
			)
		)
		(property "Author" "Antmicro"
			(at 213.275 135.7 0)
			(layer "F.Fab")
			(hide yes)
			(effects
				(font
					(size 1 1)
					(thickness 0.15)
				)
			)
		)
		(property "License" "Apache-2.0"
			(at 213.275 135.7 0)
			(layer "F.Fab")
			(hide yes)
			(effects
				(font
					(size 1 1)
					(thickness 0.15)
				)
			)
		)
		(property "MPN" "MPM54304GMN-0001"
			(at 213.275 135.7 0)
			(layer "F.Fab")
			(hide yes)
			(effects
				(font
					(size 1 1)
					(thickness 0.15)
				)
			)
		)
		(property "Manufacturer" "Monolithic Power Systems"
			(at 213.275 135.7 0)
			(layer "F.Fab")
			(hide yes)
			(effects
				(font
					(size 1 1)
					(thickness 0.15)
				)
			)
		)
		(sheetname "Power supply")
		(sheetfile "power_supply.kicad_sch")
		(solder_paste_margin_ratio -0.1)
		(attr smd)
		(fp_line
			(start 3.648 3.648)
			(end 3.648 2.922)
			(stroke
				(width 0.15)
				(type solid)
			)
			(layer "F.SilkS")
		)
		(fp_line
			(start 3.648 -3.65)
			(end 3.648 -2.926)
			(stroke
				(width 0.15)
				(type solid)
			)
			(layer "F.SilkS")
		)
		(fp_line
			(start 2.922 3.648)
			(end 3.648 3.648)
			(stroke
				(width 0.15)
				(type solid)
			)
			(layer "F.SilkS")
		)
		(fp_line
			(start 2.922 -3.65)
			(end 3.648 -3.65)
			(stroke
				(width 0.15)
				(type solid)
			)
			(layer "F.SilkS")
		)
		(fp_line
			(start -2.926 3.648)
			(end -3.65 3.648)
			(stroke
				(width 0.15)
				(type solid)
			)
			(layer "F.SilkS")
		)
		(fp_line
			(start -3.65 3.648)
			(end -3.65 2.922)
			(stroke
				(width 0.15)
				(type solid)
			)
			(layer "F.SilkS")
		)
		(fp_line
			(start -3.665 -2.928)
			(end -3.665 -3.653)
			(stroke
				(width 0.15)
				(type solid)
			)
			(layer "F.SilkS")
		)
		(fp_line
			(start -3.665 -3.653)
			(end -2.94 -3.653)
			(stroke
				(width 0.15)
				(type solid)
			)
			(layer "F.SilkS")
		)
		(fp_circle
			(center -3.8 -1.925)
			(end -3.75 -1.925)
			(stroke
				(width 0.15)
				(type solid)
			)
			(fill yes)
			(layer "F.SilkS")
		)
		(fp_rect
			(start -4 -4)
			(end 3.999 3.999)
			(stroke
				(width 0.05)
				(type solid)
			)
			(fill no)
			(layer "F.CrtYd")
		)
		(fp_line
			(start 3.499 3.499)
			(end 3.499 -3.5)
			(stroke
				(width 0.15)
				(type solid)
			)
			(layer "F.Fab")
		)
		(fp_line
			(start 3.499 -3.5)
			(end -3.5 -3.5)
			(stroke
				(width 0.15)
				(type solid)
			)
			(layer "F.Fab")
		)
		(fp_line
			(start -3.101 -3.5)
			(end -3.5 -3.101)
			(stroke
				(width 0.15)
				(type solid)
			)
			(layer "F.Fab")
		)
		(fp_line
			(start -3.5 3.499)
			(end 3.499 3.499)
			(stroke
				(width 0.15)
				(type solid)
			)
			(layer "F.Fab")
		)
		(fp_line
			(start -3.5 -3.5)
			(end -3.5 3.499)
			(stroke
				(width 0.15)
				(type solid)
			)
			(layer "F.Fab")
		)
		(pad "1" smd rect
			(at -3.138 -1.625 270)
			(size 0.3 1.125)
			(layers "F.Cu" "F.Mask" "F.Paste")
			(net 9 "/Power supply/VOUT3")
			(pinfunction "VOUT3")
			(pintype "power_out")
		)
		(pad "2" smd rect
			(at -3.138 -0.975 270)
			(size 0.3 1.125)
			(layers "F.Cu" "F.Mask" "F.Paste")
			(net 14 "GND")
			(pinfunction "GND")
			(pintype "passive")
		)
		(pad "3" smd rect
			(at -3.138 -0.328 270)
			(size 0.3 1.125)
			(layers "F.Cu" "F.Mask" "F.Paste")
			(net 38 "/Power supply/I2C.SDA")
			(pinfunction "SDA")
			(pintype "bidirectional")
		)
		(pad "4" smd rect
			(at -3.138 0.325 270)
			(size 0.3 1.125)
			(layers "F.Cu" "F.Mask" "F.Paste")
			(net 39 "/Power supply/I2C.SCL")
			(pinfunction "SCL")
			(pintype "input")
		)
		(pad "5" smd rect
			(at -3.138 0.972 270)
			(size 0.3 1.125)
			(layers "F.Cu" "F.Mask" "F.Paste")
			(net 14 "GND")
			(pinfunction "GND")
			(pintype "passive")
		)
		(pad "6" smd rect
			(at -3.138 1.624 270)
			(size 0.3 1.125)
			(layers "F.Cu" "F.Mask" "F.Paste")
			(net 71 "/Power supply/FB2")
			(pinfunction "FB2")
			(pintype "input")
		)
		(pad "7" smd rect
			(at -2.926 3.136)
			(size 0.3 1.125)
			(layers "F.Cu" "F.Mask" "F.Paste")
			(net 14 "GND")
			(pinfunction "GND")
			(pintype "passive")
		)
		(pad "8" smd rect
			(at -2.275 3.136)
			(size 0.3 1.125)
			(layers "F.Cu" "F.Mask" "F.Paste")
			(net 8 "/Power supply/VOUT2")
			(pinfunction "VOUT2")
			(pintype "power_out")
		)
		(pad "9" smd rect
			(at -1.625 3.136 180)
			(size 0.3 1.125)
			(layers "F.Cu" "F.Mask" "F.Paste")
			(net 8 "/Power supply/VOUT2")
			(pinfunction "VOUT2")
			(pintype "passive")
		)
		(pad "10" smd rect
			(at -0.975 3.136 180)
			(size 0.3 1.125)
			(layers "F.Cu" "F.Mask" "F.Paste")
			(net 14 "GND")
			(pinfunction "GND")
			(pintype "passive")
		)
		(pad "11" smd rect
			(at -0.328 3.136 180)
			(size 0.3 1.125)
			(layers "F.Cu" "F.Mask" "F.Paste")
			(net 114 "unconnected-(U8-Pad11)")
			(pinfunction "SW2")
			(pintype "power_out+no_connect")
		)
		(pad "12" smd rect
			(at 0.325 3.136 180)
			(size 0.3 1.125)
			(layers "F.Cu" "F.Mask" "F.Paste")
			(net 115 "unconnected-(U8-Pad12)")
			(pinfunction "SW1")
			(pintype "power_out+no_connect")
		)
		(pad "13" smd rect
			(at 0.972 3.136 180)
			(size 0.3 1.125)
			(layers "F.Cu" "F.Mask" "F.Paste")
			(net 14 "GND")
			(pinfunction "GND")
			(pintype "passive")
		)
		(pad "14" smd rect
			(at 1.624 3.136 180)
			(size 0.3 1.125)
			(layers "F.Cu" "F.Mask" "F.Paste")
			(net 7 "/Power supply/VOUT1")
			(pinfunction "VOUT1")
			(pintype "power_out")
		)
		(pad "15" smd rect
			(at 2.273 3.136 180)
			(size 0.3 1.125)
			(layers "F.Cu" "F.Mask" "F.Paste")
			(net 7 "/Power supply/VOUT1")
			(pinfunction "VOUT1")
			(pintype "passive")
		)
		(pad "16" smd rect
			(at 2.922 3.136 180)
			(size 0.3 1.125)
			(layers "F.Cu" "F.Mask" "F.Paste")
			(net 14 "GND")
			(pinfunction "GND")
			(pintype "passive")
		)
		(pad "17" smd rect
			(at 3.136 1.624 270)
			(size 0.3 1.125)
			(layers "F.Cu" "F.Mask" "F.Paste")
			(net 14 "GND")
			(pinfunction "SGND1")
			(pintype "power_out")
		)
		(pad "18" smd rect
			(at 3.136 0.972 270)
			(size 0.3 1.125)
			(layers "F.Cu" "F.Mask" "F.Paste")
			(net 70 "/Power supply/FB1")
			(pinfunction "FB1")
			(pintype "input")
		)
		(pad "19" smd rect
			(at 3.136 0.325 270)
			(size 0.3 1.125)
			(layers "F.Cu" "F.Mask" "F.Paste")
			(net 20 "/Power supply/PWR_EN")
			(pinfunction "EN/SYNCI")
			(pintype "input")
		)
		(pad "20" smd rect
			(at 3.136 -0.328 270)
			(size 0.3 1.125)
			(layers "F.Cu" "F.Mask" "F.Paste")
			(net 14 "GND")
			(pinfunction "GND")
			(pintype "passive")
		)
		(pad "21" smd rect
			(at 3.136 -0.975 270)
			(size 0.3 1.125)
			(layers "F.Cu" "F.Mask" "F.Paste")
			(net 14 "GND")
			(pinfunction "GND")
			(pintype "passive")
		)
		(pad "22" smd rect
			(at 3.136 -1.625 270)
			(size 0.3 1.125)
			(layers "F.Cu" "F.Mask" "F.Paste")
			(net 10 "/Power supply/VOUT4")
			(pinfunction "VOUT4")
			(pintype "power_out")
		)
		(pad "23" smd rect
			(at 2.922 -3.138)
			(size 0.3 1.125)
			(layers "F.Cu" "F.Mask" "F.Paste")
			(net 10 "/Power supply/VOUT4")
			(pinfunction "VOUT4")
			(pintype "passive")
		)
		(pad "24" smd rect
			(at 2.273 -3.138)
			(size 0.3 1.125)
			(layers "F.Cu" "F.Mask" "F.Paste")
			(net 73 "/Power supply/FB4")
			(pinfunction "FB4")
			(pintype "input")
		)
		(pad "25" smd rect
			(at 1.624 -3.138 180)
			(size 0.3 1.125)
			(layers "F.Cu" "F.Mask" "F.Paste")
			(net 117 "Net-(C12-Pad2)")
			(pinfunction "VCC")
			(pintype "input")
		)
		(pad "26" smd rect
			(at 0.972 -3.138 180)
			(size 0.3 1.125)
			(layers "F.Cu" "F.Mask" "F.Paste")
			(net 228 "/Power supply/DCDC_PWRGD")
			(pinfunction "GPIO")
			(pintype "input")
		)
		(pad "27" smd rect
			(at 0.325 -3.138 180)
			(size 0.3 1.125)
			(layers "F.Cu" "F.Mask" "F.Paste")
			(net 14 "GND")
			(pinfunction "GND")
			(pintype "passive")
		)
		(pad "28" smd rect
			(at -0.328 -3.138 180)
			(size 0.3 1.125)
			(layers "F.Cu" "F.Mask" "F.Paste")
			(net 5 "+5V")
			(pinfunction "VIN")
			(pintype "input")
		)
		(pad "29" smd rect
			(at -0.975 -3.138 180)
			(size 0.3 1.125)
			(layers "F.Cu" "F.Mask" "F.Paste")
			(net 5 "+5V")
			(pinfunction "VIN")
			(pintype "passive")
		)
		(pad "30" smd rect
			(at -1.625 -3.138 180)
			(size 0.3 1.125)
			(layers "F.Cu" "F.Mask" "F.Paste")
			(net 14 "GND")
			(pinfunction "SGND2")
			(pintype "power_out")
		)
		(pad "31" smd rect
			(at -2.275 -3.138 180)
			(size 0.3 1.125)
			(layers "F.Cu" "F.Mask" "F.Paste")
			(net 72 "/Power supply/FB3")
			(pinfunction "FB3")
			(pintype "input")
		)
		(pad "32" smd rect
			(at -2.926 -3.138 180)
			(size 0.3 1.125)
			(layers "F.Cu" "F.Mask" "F.Paste")
			(net 9 "/Power supply/VOUT3")
			(pinfunction "VOUT3")
			(pintype "passive")
		)
		(pad "33" smd rect
			(at -0.863 -0.863 180)
			(size 1.725 1.725)
			(layers "F.Cu" "F.Mask" "F.Paste")
			(net 14 "GND")
			(pinfunction "GND")
			(pintype "passive")
			(solder_paste_margin -0.1)
		)
		(pad "33" smd rect
			(at -0.863 0.86 180)
			(size 1.725 1.725)
			(layers "F.Cu" "F.Mask" "F.Paste")
			(net 14 "GND")
			(pinfunction "GND")
			(pintype "passive")
			(solder_paste_margin -0.1)
		)
		(pad "33" smd rect
			(at 0.86 -0.863 180)
			(size 1.725 1.725)
			(layers "F.Cu" "F.Mask" "F.Paste")
			(net 14 "GND")
			(pinfunction "GND")
			(pintype "passive")
			(solder_paste_margin -0.1)
		)
		(pad "33" smd rect
			(at 0.86 0.86 180)
			(size 1.725 1.725)
			(layers "F.Cu" "F.Mask" "F.Paste")
			(net 14 "GND")
			(pinfunction "GND")
			(pintype "passive")
			(solder_paste_margin -0.1)
		)
	)
	(footprint "antmicro-footprints:R_0603_1608Metric"
		(layer "F.Cu")
		(at 160.175 67.35)
		(descr "Resistor SMD 0603")
		(tags "resistor SMD 0603")
		(property "Reference" "R52"
			(at -3.575 0.45 0)
			(unlocked yes)
			(layer "F.SilkS")
			(effects
				(font
					(size 0.7 0.7)
					(thickness 0.15)
				)
				(justify left bottom)
			)
		)
		(property "Value" "R_0R_22.4A_0603"
			(at 0 1.6 0)
			(layer "F.Fab")
			(effects
				(font
					(size 0.7 0.7)
					(thickness 0.15)
				)
				(justify left bottom)
			)
		)
		(property "Author" "Antmicro"
			(at 0 0 0)
			(layer "F.Fab")
			(hide yes)
			(effects
				(font
					(size 1 1)
					(thickness 0.15)
				)
			)
		)
		(property "License" "Apache-2.0"
			(at 0 0 0)
			(layer "F.Fab")
			(hide yes)
			(effects
				(font
					(size 1 1)
					(thickness 0.15)
				)
			)
		)
		(property "MPN" "PMR03EZPJ000"
			(at 0 0 0)
			(layer "F.Fab")
			(hide yes)
			(effects
				(font
					(size 1 1)
					(thickness 0.15)
				)
			)
		)
		(property "Manufacturer" "ROHM Semiconductor"
			(at 0 0 0)
			(layer "F.Fab")
			(hide yes)
			(effects
				(font
					(size 1 1)
					(thickness 0.15)
				)
			)
		)
		(property "Max. Curr." "22.4A"
			(at 0 0 0)
			(layer "F.Fab")
			(hide yes)
			(effects
				(font
					(size 1 1)
					(thickness 0.15)
				)
			)
		)
		(property "Tolerance" "template_tolerance"
			(at 0 0 0)
			(layer "F.Fab")
			(hide yes)
			(effects
				(font
					(size 1 1)
					(thickness 0.15)
				)
			)
		)
		(property "Val" "0R"
			(at 0 0 0)
			(layer "F.Fab")
			(hide yes)
			(effects
				(font
					(size 1 1)
					(thickness 0.15)
				)
			)
		)
		(sheetname "Power supply")
		(sheetfile "power_supply.kicad_sch")
		(attr smd)
		(fp_line
			(start -0.3 -0.3)
			(end 0.3 -0.3)
			(stroke
				(width 0.15)
				(type solid)
			)
			(layer "F.SilkS")
		)
		(fp_line
			(start -0.3 0.3)
			(end 0.3 0.3)
			(stroke
				(width 0.15)
				(type solid)
			)
			(layer "F.SilkS")
		)
		(fp_rect
			(start -1.25 -0.7)
			(end 1.25 0.7)
			(stroke
				(width 0.05)
				(type solid)
			)
			(fill no)
			(layer "F.CrtYd")
		)
		(fp_rect
			(start -0.8 -0.4)
			(end 0.8 0.4)
			(stroke
				(width 0.15)
				(type solid)
			)
			(fill no)
			(layer "F.Fab")
		)
		(pad "1" smd roundrect
			(at -0.7 0)
			(size 0.6 0.8)
			(layers "F.Cu" "F.Mask" "F.Paste")
			(roundrect_rratio 0.2)
			(net 4 "+0V5")
			(pintype "passive")
		)
		(pad "2" smd roundrect
			(at 0.7 0)
			(size 0.6 0.8)
			(layers "F.Cu" "F.Mask" "F.Paste")
			(roundrect_rratio 0.2)
			(net 11 "/Power supply/VOUT")
			(pintype "passive")
		)
	)
)
